FILE_TYPE = CONNECTIVITY;
{Allegro Design Entry HDL 17.4-2019 S026 (4007227) 1/17/2022}
"PAGE_NUMBER" = 375;
0"NC";
1"GND\g";
2"GND\g";
3"P3V3_AUX\g";
4"P3V3_AUX\g";
5"P3V3_AUX\g";
6"GND\g";
7"GND\g";
8"P3V3_AUX\g";
9"P3V3_AUX\g";
10"P3V3_AUX\g";
11"GND\g";
12"GND\g";
13"GND\g";
14"P3V3_AUX\g";
15"GND\g";
16"GND\g";
17"GND\g";
18"LED_PWRGD_PVDDCR_CPU1_P1_D";
19"LED_PWRGD_PVDDCR_CPU0_P1_D";
20"LED_PWRGD_PVDDCR_CPU0_P1_R";
21"LED_PWRGD_PVDDCR_SOC_P1_D";
22"LED_PWRGD_PVDDCR_SOC_P1_R";
23"LED_PWRGD_PVDDCR_CPU1_P1_R";
24"LED_PWRGD_PVDDIO_P1_R";
25"FM_LED_PWRGD_PVDDCR_CPU0_P1";
26"FM_LED_PWRGD_PVDDCR_SOC_P1";
27"FM_LED_PWRGD_PVDDCR_CPU1_P1";
28"FM_LED_PWRGD_PVDDIO_P1";
29"LED_PWRGD_PVDD11_S3_P1_D";
30"LED_PWRGD_PVDD11_S3_P1_R";
31"FM_LED_PWRGD_PVDD11_S3_P1";
32"LED_PWRGD_PVDD18_S5_P1_D";
33"LED_PWRGD_PVDD18_S5_P1_R";
34"LED_P12V_AUX_R2";
35"LED_P12V_AUX_R3";
36"LED_P12V_AUX_R1";
37"FM_LED_PWRGD_PVDD18_S5_P1";
38"LED_PWRGD_PVDDIO_P1_D";
39"LED_P12V_SCM_FAULT_D2";
40"LED_P12V_SCM_FAULT";
41"P12V_AUX\g";
42"P3V3_AUX\g";
43"P12V_SCM_FAULT_R_N";
44"LED_P12V_SCM_FAULT_D1";
45"LED_P12V_PSU_R3";
46"LED_P12V_PSU_R2";
47"P12V_PSU\g";
48"LED_P12V_PSU_R1";
%"UNIVERSAL_GND"
"1","(-7875,1500)","0","pure_quanta_power","I1";
;
CDS_LIB"pure_quanta_power"
HDL_POWER"GND";
"A"1;
%"MOSFET_NCH_DUAL"
"2","(-7925,4400)","0","pure_quanta","I10";
;
LOCATION"Q84"
SEC"2"
VALUE"PJT138K"
PART_TYPE"SMLF"
MATERIAL"IC"
CDS_LMAN_SYM_OUTLINE"-150,150,150,-150"
NEEDS_NO_SIZE"TRUE"
CDS_LIB"pure_quanta"
SEC_TYPE""
PART_NUMBER"BAM138K0003";
"S2"
$PN"4"17;
"G2"
$PN"5"26;
"D2"
$PN"3"21;
%"MOSFET_NCH_DUAL"
"1","(-7925,5725)","0","pure_quanta","I11";
;
LOCATION"Q84"
$SEC"1"
CDS_SEC"1"
MATERIAL"IC"
PART_TYPE"SMLF"
VALUE"PJT138K"
NEEDS_NO_SIZE"TRUE"
CDS_LMAN_SYM_OUTLINE"-150,150,150,-150"
CDS_LIB"pure_quanta"
PART_NUMBER"BAM138K0003";
"D1"
$PN"6"19;
"G1"
$PN"2"25;
"S1"
$PN"1"2;
%"UNIVERSAL_GND"
"1","(-7875,5375)","0","pure_quanta_power","I12";
;
CDS_LIB"pure_quanta_power"
HDL_POWER"GND";
"A"2;
%"Q_LED"
"1","(-6850,2125)","2","pure_quanta","I13";
;
LOCATION"D83"
$SEC"1"
CDS_SEC"1"
MATERIAL"IC"
PACK_TYPE"SMLF"
COLOR"LED_BLUE"
MANUF_PN"LTST-C281TBKT-5A"
CDS_LIB"pure_quanta"
NEEDS_NO_SIZE"TRUE"
PART_NUMBER"BEBL0172Z00";
"A"
$PN"A"24;
"C"
$PN"C"38;
%"Q_LED"
"1","(-6850,3450)","2","pure_quanta","I14";
;
LOCATION"D82"
$SEC"1"
CDS_SEC"1"
MANUF_PN"LTST-C281TBKT-5A"
COLOR"LED_BLUE"
PACK_TYPE"SMLF"
MATERIAL"IC"
NEEDS_NO_SIZE"TRUE"
CDS_LIB"pure_quanta"
PART_NUMBER"BEBL0172Z00";
"A"
$PN"A"23;
"C"
$PN"C"18;
%"Q_RES"
"1","(-5475,2125)","0","pure_quanta","I15";
;
LOCATION"R3095"
$SEC"1"
CDS_SEC"1"
MATERIAL"CHIP"
WATTAGE"1/16W"
PACK_TYPE"0402LF"
TOLERANCE"1%"
VALUE"130"
CDS_LIB"pure_quanta"
PART_NUMBER"CS11302FB03";
"B"
$PN"2"3;
"A"
$PN"1"24;
%"Q_RES"
"1","(-5425,3450)","0","pure_quanta","I16";
;
LOCATION"R3096"
$SEC"1"
CDS_SEC"1"
PACK_TYPE"0402LF"
WATTAGE"1/16W"
MATERIAL"CHIP"
TOLERANCE"1%"
VALUE"130"
CDS_LIB"pure_quanta"
PART_NUMBER"CS11302FB03";
"B"
$PN"2"4;
"A"
$PN"1"23;
%"Q_LED"
"1","(-6850,4675)","2","pure_quanta","I17";
;
LOCATION"D81"
$SEC"1"
CDS_SEC"1"
PACK_TYPE"SMLF"
MATERIAL"IC"
COLOR"LED_BLUE"
MANUF_PN"LTST-C281TBKT-5A"
CDS_LIB"pure_quanta"
NEEDS_NO_SIZE"TRUE"
PART_NUMBER"BEBL0172Z00";
"A"
$PN"A"22;
"C"
$PN"C"21;
%"Q_RES"
"1","(-5475,4675)","0","pure_quanta","I18";
;
LOCATION"R3094"
$SEC"1"
CDS_SEC"1"
WATTAGE"1/16W"
MATERIAL"CHIP"
TOLERANCE"1%"
VALUE"130"
PACK_TYPE"0402LF"
CDS_LIB"pure_quanta"
PART_NUMBER"CS11302FB03";
"B"
$PN"2"5;
"A"
$PN"1"22;
%"Q_LED"
"1","(-6850,6000)","2","pure_quanta","I19";
;
LOCATION"D80"
$SEC"1"
CDS_SEC"1"
MATERIAL"IC"
COLOR"LED_BLUE"
MANUF_PN"LTST-C281TBKT-5A"
PACK_TYPE"SMLF"
CDS_LIB"pure_quanta"
NEEDS_NO_SIZE"TRUE"
PART_NUMBER"BEBL0172Z00";
"A"
$PN"A"20;
"C"
$PN"C"19;
%"MOSFET_NCH_DUAL"
"2","(-7925,1850)","0","pure_quanta","I2";
;
LOCATION"Q85"
SEC"2"
PART_TYPE"SMLF"
VALUE"PJT138K"
MATERIAL"IC"
SEC_TYPE""
CDS_LIB"pure_quanta"
NEEDS_NO_SIZE"TRUE"
CDS_LMAN_SYM_OUTLINE"-150,150,150,-150"
PART_NUMBER"BAM138K0003";
"S2"
$PN"4"1;
"G2"
$PN"5"28;
"D2"
$PN"3"38;
%"Q_RES"
"1","(-5500,6000)","0","pure_quanta","I20";
;
LOCATION"R3093"
$SEC"1"
CDS_SEC"1"
PACK_TYPE"0402LF"
WATTAGE"1/16W"
MATERIAL"CHIP"
TOLERANCE"1%"
VALUE"130"
CDS_LIB"pure_quanta"
PART_NUMBER"CS11302FB03";
"B"
$PN"2"8;
"A"
$PN"1"20;
%"UNIVERSAL_POWER"
"1","(-4875,2275)","0","pure_quanta_power","I21";
;
HDL_POWER"P3V3_AUX"
CDS_LIB"pure_quanta_power";
"A"3;
%"UNIVERSAL_POWER"
"1","(-4825,3625)","0","pure_quanta_power","I22";
;
HDL_POWER"P3V3_AUX"
CDS_LIB"pure_quanta_power";
"A"4;
%"UNIVERSAL_POWER"
"1","(-4875,4800)","0","pure_quanta_power","I26";
;
HDL_POWER"P3V3_AUX"
CDS_LIB"pure_quanta_power";
"A"5;
%"UNIVERSAL_GND"
"1","(-3200,4075)","0","pure_quanta_power","I28";
;
CDS_LIB"pure_quanta_power"
HDL_POWER"GND";
"A"6;
%"MOSFET_NCH_DUAL"
"2","(-3250,4425)","0","pure_quanta","I29";
;
LOCATION"Q86"
SEC"2"
VALUE"PJT138K"
PART_TYPE"SMLF"
MATERIAL"IC"
CDS_LMAN_SYM_OUTLINE"-150,150,150,-150"
CDS_LIB"pure_quanta"
SEC_TYPE""
NEEDS_NO_SIZE"TRUE"
PART_NUMBER"BAM138K0003";
"S2"
$PN"4"6;
"G2"
$PN"5"37;
"D2"
$PN"3"32;
%"MOSFET_NCH_DUAL"
"1","(-3250,5750)","0","pure_quanta","I30";
;
LOCATION"Q86"
$SEC"1"
CDS_SEC"1"
MATERIAL"IC"
PART_TYPE"SMLF"
VALUE"PJT138K"
NEEDS_NO_SIZE"TRUE"
CDS_LMAN_SYM_OUTLINE"-150,150,150,-150"
CDS_LIB"pure_quanta"
PART_NUMBER"BAM138K0003";
"D1"
$PN"6"29;
"G1"
$PN"2"31;
"S1"
$PN"1"7;
%"UNIVERSAL_GND"
"1","(-3200,5400)","0","pure_quanta_power","I31";
;
CDS_LIB"pure_quanta_power"
HDL_POWER"GND";
"A"7;
%"Q_LED"
"1","(-2175,4700)","2","pure_quanta","I33";
;
LOCATION"D85"
$SEC"1"
CDS_SEC"1"
MANUF_PN"LTST-C281TBKT-5A"
COLOR"LED_BLUE"
MATERIAL"IC"
PACK_TYPE"SMLF"
CDS_LIB"pure_quanta"
NEEDS_NO_SIZE"TRUE"
PART_NUMBER"BEBL0172Z00";
"A"
$PN"A"33;
"C"
$PN"C"32;
%"UNIVERSAL_POWER"
"1","(-4850,6150)","0","pure_quanta_power","I34";
;
HDL_POWER"P3V3_AUX"
CDS_LIB"pure_quanta_power";
"A"8;
%"Q_LED"
"1","(-2175,6025)","2","pure_quanta","I35";
;
LOCATION"D84"
$SEC"1"
CDS_SEC"1"
COLOR"LED_BLUE"
MATERIAL"IC"
MANUF_PN"LTST-C281TBKT-5A"
PACK_TYPE"SMLF"
NEEDS_NO_SIZE"TRUE"
CDS_LIB"pure_quanta"
PART_NUMBER"BEBL0172Z00";
"A"
$PN"A"30;
"C"
$PN"C"29;
%"Q_RES"
"1","(-875,4700)","0","pure_quanta","I38";
;
LOCATION"R3097"
$SEC"1"
CDS_SEC"1"
PACK_TYPE"0402LF"
WATTAGE"1/16W"
MATERIAL"CHIP"
TOLERANCE"1%"
VALUE"130"
CDS_LIB"pure_quanta"
PART_NUMBER"CS11302FB03";
"B"
$PN"2"9;
"A"
$PN"1"33;
%"UNIVERSAL_POWER"
"1","(-225,4850)","0","pure_quanta_power","I39";
;
HDL_POWER"P3V3_AUX"
CDS_LIB"pure_quanta_power";
"A"9;
%"Q_RES"
"1","(-850,6025)","0","pure_quanta","I40";
;
LOCATION"R3099"
$SEC"1"
CDS_SEC"1"
PACK_TYPE"0402LF"
WATTAGE"1/16W"
MATERIAL"CHIP"
TOLERANCE"1%"
VALUE"130"
CDS_LIB"pure_quanta"
PART_NUMBER"CS11302FB03";
"B"
$PN"2"10;
"A"
$PN"1"30;
%"UNIVERSAL_POWER"
"1","(-250,6200)","0","pure_quanta_power","I41";
;
HDL_POWER"P3V3_AUX"
CDS_LIB"pure_quanta_power";
"A"10;
%"Q_LED"
"1","(-4100,3575)","2","pure_quanta","I42";
;
LOCATION"D8000"
SEC"1"
PACK_TYPE"SMLF"
MATERIAL"IC"
COLOR"LED_BLUE"
MANUF_PN"LTST-C281TBKT-5A"
SEC_TYPE"SMLF"
NEEDS_NO_SIZE"TRUE"
CDS_LIB"pure_quanta"
PART_NUMBER"BEBL0172Z00";
"A"
$PN"A"36;
"C"
$PN"C"11;
%"UNIVERSAL_GND"
"1","(-4525,3375)","0","pure_quanta_power","I43";
;
CDS_LIB"pure_quanta_power"
HDL_POWER"GND";
"A"11;
%"Q_RES"
"1","(-3000,3575)","0","pure_quanta","I44";
;
LOCATION"R8022"
SEC"1"
PACK_TYPE"0402LF"
MATERIAL"CHIP"
VALUE"560"
TOLERANCE"1%"
WATTAGE"1/16W"
SEC_TYPE"0402LF"
CDS_LIB"pure_quanta"
PART_NUMBER"CS15602FB03";
"B"
$PN"2"34;
"A"
$PN"1"36;
%"Q_RES"
"1","(-2075,3575)","0","pure_quanta","I45";
;
LOCATION"R8023"
SEC"1"
TOLERANCE"1%"
MATERIAL"CHIP"
PACK_TYPE"0402LF"
VALUE"560"
WATTAGE"1/16W"
SEC_TYPE"0402LF"
CDS_LIB"pure_quanta"
PART_NUMBER"CS15602FB03";
"B"
$PN"2"35;
"A"
$PN"1"34;
%"Q_RES"
"1","(-1075,3575)","0","pure_quanta","I46";
;
LOCATION"R8024"
SEC"1"
PACK_TYPE"0402LF"
MATERIAL"CHIP"
TOLERANCE"1%"
VALUE"560"
WATTAGE"1/16W"
SEC_TYPE"0402LF"
CDS_LIB"pure_quanta"
PART_NUMBER"CS15602FB03";
"B"
$PN"2"41;
"A"
$PN"1"35;
%"UNIVERSAL_POWER"
"1","(-775,3825)","0","pure_quanta_power","I47";
;
HDL_POWER"P12V_AUX"
CDS_LIB"pure_quanta_power";
"A"41;
%"UNIVERSAL_POWER"
"1","(-700,2675)","0","pure_quanta_power","I48";
;
HDL_POWER"P12V_PSU"
CDS_LIB"pure_quanta_power";
"A"47;
%"Q_RES"
"1","(-1000,2425)","0","pure_quanta","I49";
;
LOCATION"R8027"
SEC"1"
PACK_TYPE"0402LF"
TOLERANCE"1%"
VALUE"560"
MATERIAL"CHIP"
WATTAGE"1/16W"
SEC_TYPE"0402LF"
CDS_LIB"pure_quanta"
PART_NUMBER"CS15602FB03";
"B"
$PN"2"47;
"A"
$PN"1"45;
%"Q_RES"
"1","(-2000,2425)","0","pure_quanta","I50";
;
LOCATION"R8026"
SEC"1"
WATTAGE"1/16W"
PACK_TYPE"0402LF"
TOLERANCE"1%"
VALUE"560"
MATERIAL"CHIP"
SEC_TYPE"0402LF"
CDS_LIB"pure_quanta"
PART_NUMBER"CS15602FB03";
"B"
$PN"2"45;
"A"
$PN"1"46;
%"Q_RES"
"1","(-2925,2425)","0","pure_quanta","I51";
;
LOCATION"R8025"
SEC"1"
PACK_TYPE"0402LF"
TOLERANCE"1%"
WATTAGE"1/16W"
VALUE"560"
MATERIAL"CHIP"
SEC_TYPE"0402LF"
CDS_LIB"pure_quanta"
PART_NUMBER"CS15602FB03";
"B"
$PN"2"46;
"A"
$PN"1"48;
%"Q_LED"
"1","(-4025,2425)","2","pure_quanta","I52";
;
LOCATION"D8001"
SEC"1"
PACK_TYPE"SMLF"
MANUF_PN"LTST-C281TBKT-5A"
MATERIAL"IC"
COLOR"LED_BLUE"
SEC_TYPE"SMLF"
NEEDS_NO_SIZE"TRUE"
CDS_LIB"pure_quanta"
PART_NUMBER"BEBL0172Z00";
"A"
$PN"A"48;
"C"
$PN"C"12;
%"UNIVERSAL_GND"
"1","(-4450,2225)","0","pure_quanta_power","I53";
;
CDS_LIB"pure_quanta_power"
HDL_POWER"GND";
"A"12;
%"UNIVERSAL_POWER"
"1","(-325,1750)","0","pure_quanta_power","I54";
;
HDL_POWER"P3V3_AUX"
CDS_LIB"pure_quanta_power";
"A"42;
%"Q_RES"
"1","(-775,1500)","0","pure_quanta","I55";
;
LOCATION"R8029"
SEC"1"
WATTAGE"1/16W"
VALUE"249"
MATERIAL"CHIP"
TOLERANCE"1%"
PACK_TYPE"0402LF"
CDS_LIB"pure_quanta"
SEC_TYPE"0402LF"
PART_NUMBER"CS12492FB02";
"B"
$PN"2"42;
"A"
$PN"1"40;
%"Q_LED"
"1","(-1725,1500)","2","pure_quanta","I56";
;
LOCATION"D8002"
SEC"1"
COLOR"LED_YELLOW"
MANUF_PN"LTST-C190KSKT-P"
MATERIAL"IC"
PACK_TYPE"SMLF"
NEEDS_NO_SIZE"TRUE"
CDS_LIB"pure_quanta"
SEC_TYPE"SMLF"
PART_NUMBER"BEYL0159Z00";
"A"
$PN"A"40;
"C"
$PN"C"39;
%"MOSFET_NCH_DUAL"
"1","(-3075,750)","0","pure_quanta","I57";
;
LOCATION"Q8001"
SEC"1"
MATERIAL"IC"
VALUE"PJT138K"
PART_TYPE"SMLF"
SEC_TYPE""
CDS_LIB"pure_quanta"
NEEDS_NO_SIZE"TRUE"
CDS_LMAN_SYM_OUTLINE"-150,150,150,-150"
PART_NUMBER"BAM138K0003";
"D1"
$PN"6"44;
"G1"
$PN"2"43;
"S1"
$PN"1"15;
%"MOSFET_NCH_DUAL"
"2","(-2100,1175)","0","pure_quanta","I58";
;
LOCATION"Q8001"
SEC"2"
MATERIAL"IC"
PART_TYPE"SMLF"
VALUE"PJT138K"
SEC_TYPE""
CDS_LMAN_SYM_OUTLINE"-150,150,150,-150"
NEEDS_NO_SIZE"TRUE"
CDS_LIB"pure_quanta"
PART_NUMBER"BAM138K0003";
"S2"
$PN"4"13;
"G2"
$PN"5"44;
"D2"
$PN"3"39;
%"UNIVERSAL_GND"
"1","(-2050,675)","0","pure_quanta_power","I59";
;
CDS_LIB"pure_quanta_power"
HDL_POWER"GND";
"A"13;
%"UNIVERSAL_POWER"
"1","(-3025,1625)","0","pure_quanta_power","I60";
;
HDL_POWER"P3V3_AUX"
CDS_LIB"pure_quanta_power";
"A"14;
%"UNIVERSAL_GND"
"1","(-3025,375)","0","pure_quanta_power","I61";
;
CDS_LIB"pure_quanta_power"
HDL_POWER"GND";
"A"15;
%"Q_RES"
"2","(-3025,1425)","2","pure_quanta","I62";
;
LOCATION"R8028"
$SEC"1"
CDS_SEC"1"
VALUE"4.7K"
MATERIAL"CHIP"
WATTAGE"1/16W"
TOLERANCE"5%"
PACK_TYPE"0402LF"
CDS_LIB"pure_quanta"
PART_NUMBER"CS24702JB10";
"A"
$PN"1"14;
"B"
$PN"2"44;
%"MOSFET_NCH_DUAL"
"1","(-7925,3175)","0","pure_quanta","I7";
;
LOCATION"Q85"
$SEC"1"
CDS_SEC"1"
MATERIAL"IC"
VALUE"PJT138K"
PART_TYPE"SMLF"
NEEDS_NO_SIZE"TRUE"
CDS_LMAN_SYM_OUTLINE"-150,150,150,-150"
CDS_LIB"pure_quanta"
PART_NUMBER"BAM138K0003";
"D1"
$PN"6"18;
"G1"
$PN"2"27;
"S1"
$PN"1"16;
%"UNIVERSAL_GND"
"1","(-7875,2825)","0","pure_quanta_power","I8";
;
CDS_LIB"pure_quanta_power"
HDL_POWER"GND";
"A"16;
%"UNIVERSAL_GND"
"1","(-7875,4050)","0","pure_quanta_power","I9";
;
CDS_LIB"pure_quanta_power"
HDL_POWER"GND";
"A"17;
END.
